FILE_TYPE = CONNECTIVITY;
{Allegro Design Entry HDL 17.4-2019 S026 (4007227) 1/17/2022}
"PAGE_NUMBER" = 85;
0"NC";
1"GND\g";
2"GND\g";
3"P3V3\g";
4"P3V3\g";
5"P3V3_AUX\g";
6"M_A_CPU0_SB_CB<7:0>";
7"M_A_CPU0_SA_CB<7:0>";
8"M_A_CPU0_SB_DQ<31:0>";
9"M_A_CPU0_SB_CA<6:0>";
10"M_A_CPU0_SA_CA<6:0>";
11"M_A_CPU0_SA_DQ<31:0>";
12"M_A_CPU0_SB_DQS_DP<9:0>";
13"M_A_CPU0_SA_DQS_DN<9:0>";
14"M_A_CPU0_SA_DQS_DP<9:0>";
15"M_A_CPU0_SB_DQS_DN<9:0>";
16"M_A_CPU0_ALERT_N";
17"I3C_SPD_DDRAF_CPU0_SCL";
18"I3C_SPD_DDRAF_CPU0_SDA";
19"PD_CHA_CPU0_DIMM0_SAA";
20"P3V3_AUX\g";
21"M_A_CPU0_CLK_DN<0>";
22"M_A_CPU0_SB_CS_N<0>";
23"M_A_CPU0_SA_CB<5>";
24"M_A_CPU0_CLK_DP<0>";
25"GND\g";
26"GND\g";
27"GND\g";
28"P12V_MEM_CPU0\g";
29"P3V3_AUX\g";
30"P3V3_AUX\g";
31"I3C_SPD_DDRA_CPU0_SDA";
32"I3C_SPD_DDRA_CPU0_SCL";
33"PWRGD_CHA_CPU0_DIMM0";
34"M_A_CPU0_RESET_N";
35"M_A_CPU0_SA_CB<1>";
36"M_A_CPU0_SA_CB<2>";
37"M_A_CPU0_SA_DQ<9>";
38"M_A_CPU0_SA_DQ<10>";
39"M_A_CPU0_SA_DQ<11>";
40"M_A_CPU0_SA_DQ<13>";
41"M_A_CPU0_SB_RSP<0>";
42"M_A_CPU0_SB_DQ<4>";
43"M_A_CPU0_SB_DQ<3>";
44"M_A_CPU0_SB_DQ<0>";
45"M_A_CPU0_SB_DQS_DN<1>";
46"M_A_CPU0_SB_DQS_DN<0>";
47"M_A_CPU0_SB_CB<6>";
48"M_A_CPU0_SB_DQS_DP<8>";
49"M_A_CPU0_SB_DQS_DN<9>";
50"M_A_CPU0_SA_DQS_DN<0>";
51"M_A_CPU0_SA_DQS_DP<0>";
52"M_A_CPU0_SA_DQ<0>";
53"M_A_CPU0_SB_DQ<30>";
54"M_A_CPU0_SB_DQ<25>";
55"M_A_CPU0_SA_DQ<3>";
56"M_A_CPU0_SB_DQ<2>";
57"M_A_CPU0_SB_DQ<13>";
58"M_A_CPU0_SB_CA<2>";
59"M_A_CPU0_SB_CB<2>";
60"M_A_CPU0_SA_CA<3>";
61"M_A_CPU0_SA_DQ<17>";
62"M_A_CPU0_SA_CA<0>";
63"M_A_CPU0_SB_CB<1>";
64"M_A_CPU0_SB_PAR";
65"M_A_CPU0_SA_CB<3>";
66"M_A_CPU0_SA_CB<4>";
67"M_A_CPU0_SB_DQS_DP<9>";
68"M_A_CPU0_SA_DQS_DN<6>";
69"M_A_CPU0_SA_DQS_DP<6>";
70"M_A_CPU0_SA_DQS_DN<7>";
71"M_A_CPU0_SA_DQ<14>";
72"M_A_CPU0_SA_DQ<15>";
73"M_A_CPU0_SA_DQ<20>";
74"M_A_CPU0_SA_DQ<24>";
75"M_A_CPU0_SA_DQ<25>";
76"M_A_CPU0_SA_DQ<26>";
77"M_A_CPU0_SA_DQ<27>";
78"M_A_CPU0_SA_DQ<28>";
79"M_A_CPU0_SA_DQ<29>";
80"M_A_CPU0_SB_DQS_DN<8>";
81"M_A_CPU0_SB_DQS_DP<7>";
82"M_A_CPU0_SB_DQS_DN<7>";
83"M_A_CPU0_SB_DQS_DP<6>";
84"M_A_CPU0_SB_DQS_DN<6>";
85"M_A_CPU0_SB_DQS_DN<5>";
86"M_A_CPU0_SB_DQS_DP<4>";
87"M_A_CPU0_SB_DQS_DN<4>";
88"M_A_CPU0_SA_DQ<16>";
89"M_A_CPU0_SA_CS_N<1>";
90"M_A_CPU0_SA_CA<6>";
91"M_A_CPU0_SA_DQ<31>";
92"M_A_CPU0_SB_CA<5>";
93"M_A_CPU0_SA_DQS_DP<9>";
94"M_A_CPU0_SA_DQS_DN<9>";
95"M_A_CPU0_SA_DQ<30>";
96"M_A_CPU0_SA_DQS_DP<8>";
97"M_A_CPU0_SA_DQS_DN<8>";
98"M_A_CPU0_SA_DQS_DP<7>";
99"M_A_CPU0_SB_DQS_DP<5>";
100"M_A_CPU0_SA_DQS_DP<5>";
101"M_A_CPU0_SA_DQS_DN<5>";
102"M_A_CPU0_SA_DQS_DP<4>";
103"M_A_CPU0_SA_DQS_DN<4>";
104"M_A_CPU0_SB_DQS_DP<3>";
105"M_A_CPU0_SB_DQS_DN<3>";
106"M_A_CPU0_SA_DQS_DP<3>";
107"M_A_CPU0_SA_DQS_DN<3>";
108"M_A_CPU0_SB_DQS_DP<2>";
109"M_A_CPU0_SB_DQS_DN<2>";
110"M_A_CPU0_SA_DQS_DP<2>";
111"M_A_CPU0_SA_DQS_DN<2>";
112"M_A_CPU0_SB_DQS_DP<1>";
113"M_A_CPU0_SA_DQS_DP<1>";
114"M_A_CPU0_SA_DQS_DN<1>";
115"M_A_CPU0_SB_DQS_DP<0>";
116"M_A_CPU0_SA_CA<5>";
117"M_A_CPU0_SB_CA<1>";
118"M_A_CPU0_SB_CA<4>";
119"M_A_CPU0_SA_CA<4>";
120"M_A_CPU0_SA_PAR";
121"M_A_CPU0_SB_DQ<1>";
122"M_A_CPU0_SB_DQ<5>";
123"M_A_CPU0_SB_DQ<6>";
124"M_A_CPU0_SB_DQ<7>";
125"M_A_CPU0_SB_DQ<8>";
126"M_A_CPU0_SB_DQ<9>";
127"M_A_CPU0_SB_DQ<10>";
128"M_A_CPU0_SB_DQ<11>";
129"M_A_CPU0_SB_DQ<12>";
130"M_A_CPU0_SB_DQ<14>";
131"M_A_CPU0_SB_DQ<15>";
132"M_A_CPU0_SB_DQ<16>";
133"M_A_CPU0_SB_DQ<17>";
134"M_A_CPU0_SB_DQ<20>";
135"M_A_CPU0_SB_DQ<21>";
136"M_A_CPU0_SB_DQ<22>";
137"M_A_CPU0_SB_DQ<23>";
138"M_A_CPU0_SB_DQ<24>";
139"M_A_CPU0_SB_DQ<26>";
140"M_A_CPU0_SB_DQ<27>";
141"M_A_CPU0_SB_DQ<28>";
142"M_A_CPU0_SB_DQ<29>";
143"M_A_CPU0_SB_DQ<31>";
144"M_A_CPU0_SA_DQ<1>";
145"M_A_CPU0_SA_DQ<2>";
146"M_A_CPU0_SA_DQ<4>";
147"M_A_CPU0_SA_DQ<5>";
148"M_A_CPU0_SA_DQ<6>";
149"M_A_CPU0_SA_DQ<7>";
150"M_A_CPU0_SA_DQ<8>";
151"M_A_CPU0_SA_DQ<12>";
152"M_A_CPU0_SA_DQ<18>";
153"M_A_CPU0_SA_DQ<19>";
154"M_A_CPU0_SA_DQ<21>";
155"M_A_CPU0_SA_DQ<22>";
156"M_A_CPU0_SA_DQ<23>";
157"M_A_CPU0_SB_CB<0>";
158"M_A_CPU0_SB_CB<4>";
159"M_A_CPU0_SB_CB<5>";
160"M_A_CPU0_SA_CB<6>";
161"M_A_CPU0_SB_CA<6>";
162"M_A_CPU0_SB_CA<3>";
163"M_A_CPU0_SA_CA<2>";
164"M_A_CPU0_SA_CA<1>";
165"M_A_CPU0_SB_CA<0>";
166"M_A_CPU0_SA_CB<7>";
167"M_A_CPU0_SB_DQ<19>";
168"M_A_CPU0_SB_DQ<18>";
169"PD_CHA_CPU0_DIMM0_SAA";
170"PWRGD_CHAF_CPU0_R1";
171"PWRGD_CHAF_CPU0_R2";
172"PWRGD_CHAF_CPU0";
173"PWRGD_CHAF_CPU0";
174"PWRGD_CHAF_CPU0";
175"M_A_CPU0_SA_RSP<0>";
176"M_A_CPU0_SA_CB<0>";
177"M_A_CPU0_SB_CB<7>";
178"M_A_CPU0_SA_CS_N<0>";
179"M_A_CPU0_SB_CS_N<1>";
180"M_A_CPU0_SB_CB<3>";
%"GND"
"1","(-650,1750)","0","mstr_symbols","I115";
;
VOLTAGE"0.0"
CDS_LIB"mstr_symbols"
SIZE"1B"
BODY_TYPE"PLUMBING"
HDL_POWER"GND";
"A\NAC"25;
%"GND"
"1","(-2250,1950)","0","mstr_symbols","I116";
;
VOLTAGE"0.0"
CDS_LIB"mstr_symbols"
SIZE"1B"
BODY_TYPE"PLUMBING"
HDL_POWER"GND";
"A\NAC"26;
%"TAP"
"1","(-7750,4025)","2","mstr_standard","I210";
;
CDS_LIB"mstr_standard"
BODY_TYPE"PLUMBING"
HDL_TAP"TRUE";
"B \NAC \NWC"7;
"S \NAC"
BN"7"166;
%"TAP"
"1","(-7750,3925)","2","mstr_standard","I211";
;
CDS_LIB"mstr_standard"
BODY_TYPE"PLUMBING"
HDL_TAP"TRUE";
"B \NAC \NWC"7;
"S \NAC"
BN"5"23;
%"TAP"
"1","(-7750,3975)","2","mstr_standard","I212";
;
CDS_LIB"mstr_standard"
BODY_TYPE"PLUMBING"
HDL_TAP"TRUE";
"B \NAC \NWC"7;
"S \NAC"
BN"6"160;
%"TAP"
"1","(-7750,3825)","2","mstr_standard","I213";
;
CDS_LIB"mstr_standard"
BODY_TYPE"PLUMBING"
HDL_TAP"TRUE";
"B \NAC \NWC"7;
"S \NAC"
BN"3"65;
%"TAP"
"1","(-7750,3875)","2","mstr_standard","I214";
;
CDS_LIB"mstr_standard"
BODY_TYPE"PLUMBING"
HDL_TAP"TRUE";
"B \NAC \NWC"7;
"S \NAC"
BN"4"66;
%"TAP"
"1","(-7750,3775)","2","mstr_standard","I215";
;
CDS_LIB"mstr_standard"
BODY_TYPE"PLUMBING"
HDL_TAP"TRUE";
"B \NAC \NWC"7;
"S \NAC"
BN"2"36;
%"TAP"
"1","(-7750,3725)","2","mstr_standard","I216";
;
CDS_LIB"mstr_standard"
BODY_TYPE"PLUMBING"
HDL_TAP"TRUE";
"B \NAC \NWC"7;
"S \NAC"
BN"1"35;
%"TAP"
"1","(-7750,3675)","2","mstr_standard","I217";
;
CDS_LIB"mstr_standard"
BODY_TYPE"PLUMBING"
HDL_TAP"TRUE";
"B \NAC \NWC"7;
"S \NAC"
BN"0"176;
%"TAP"
"1","(-7750,5375)","2","mstr_standard","I227";
;
CDS_LIB"mstr_standard"
BODY_TYPE"PLUMBING"
HDL_TAP"TRUE";
"B \NAC \NWC"10;
"S \NAC"
BN"5"116;
%"TAP"
"1","(-7750,5325)","2","mstr_standard","I228";
;
CDS_LIB"mstr_standard"
BODY_TYPE"PLUMBING"
HDL_TAP"TRUE";
"B \NAC \NWC"10;
"S \NAC"
BN"4"119;
%"TAP"
"1","(-7750,5425)","2","mstr_standard","I229";
;
CDS_LIB"mstr_standard"
BODY_TYPE"PLUMBING"
HDL_TAP"TRUE";
"B \NAC \NWC"10;
"S \NAC"
BN"6"90;
%"TAP"
"1","(-7750,5275)","2","mstr_standard","I230";
;
CDS_LIB"mstr_standard"
BODY_TYPE"PLUMBING"
HDL_TAP"TRUE";
"B \NAC \NWC"10;
"S \NAC"
BN"3"60;
%"TAP"
"1","(-7750,5225)","2","mstr_standard","I231";
;
CDS_LIB"mstr_standard"
BODY_TYPE"PLUMBING"
HDL_TAP"TRUE";
"B \NAC \NWC"10;
"S \NAC"
BN"2"163;
%"TAP"
"1","(-7750,5175)","2","mstr_standard","I232";
;
CDS_LIB"mstr_standard"
BODY_TYPE"PLUMBING"
HDL_TAP"TRUE";
"B \NAC \NWC"10;
"S \NAC"
BN"1"164;
%"TAP"
"1","(-7750,5125)","2","mstr_standard","I233";
;
CDS_LIB"mstr_standard"
BODY_TYPE"PLUMBING"
HDL_TAP"TRUE";
"B \NAC \NWC"10;
"S \NAC"
BN"0"62;
%"TAP"
"1","(-7750,5025)","2","mstr_standard","I235";
;
CDS_LIB"mstr_standard"
BODY_TYPE"PLUMBING"
HDL_TAP"TRUE";
"B \NAC \NWC"9;
"S \NAC"
BN"6"161;
%"TAP"
"1","(-7750,4975)","2","mstr_standard","I236";
;
CDS_LIB"mstr_standard"
BODY_TYPE"PLUMBING"
HDL_TAP"TRUE";
"B \NAC \NWC"9;
"S \NAC"
BN"5"92;
%"TAP"
"1","(-7750,4925)","2","mstr_standard","I237";
;
CDS_LIB"mstr_standard"
BODY_TYPE"PLUMBING"
HDL_TAP"TRUE";
"B \NAC \NWC"9;
"S \NAC"
BN"4"118;
%"TAP"
"1","(-7750,4825)","2","mstr_standard","I238";
;
CDS_LIB"mstr_standard"
BODY_TYPE"PLUMBING"
HDL_TAP"TRUE";
"B \NAC \NWC"9;
"S \NAC"
BN"2"58;
%"TAP"
"1","(-7750,4725)","2","mstr_standard","I239";
;
CDS_LIB"mstr_standard"
BODY_TYPE"PLUMBING"
HDL_TAP"TRUE";
"B \NAC \NWC"9;
"S \NAC"
BN"0"165;
%"TAP"
"1","(-7750,4775)","2","mstr_standard","I240";
;
CDS_LIB"mstr_standard"
BODY_TYPE"PLUMBING"
HDL_TAP"TRUE";
"B \NAC \NWC"9;
"S \NAC"
BN"1"117;
%"TAP"
"1","(-7750,4875)","2","mstr_standard","I241";
;
CDS_LIB"mstr_standard"
BODY_TYPE"PLUMBING"
HDL_TAP"TRUE";
"B \NAC \NWC"9;
"S \NAC"
BN"3"162;
%"TAP"
"1","(-7750,3575)","2","mstr_standard","I367";
;
CDS_LIB"mstr_standard"
BODY_TYPE"PLUMBING"
HDL_TAP"TRUE";
"B \NAC \NWC"6;
"S \NAC"
BN"7"177;
%"TAP"
"1","(-7750,3525)","2","mstr_standard","I368";
;
CDS_LIB"mstr_standard"
BODY_TYPE"PLUMBING"
HDL_TAP"TRUE";
"B \NAC \NWC"6;
"S \NAC"
BN"6"47;
%"TAP"
"1","(-7750,3475)","2","mstr_standard","I369";
;
CDS_LIB"mstr_standard"
BODY_TYPE"PLUMBING"
HDL_TAP"TRUE";
"B \NAC \NWC"6;
"S \NAC"
BN"5"159;
%"TAP"
"1","(-7750,3425)","2","mstr_standard","I370";
;
CDS_LIB"mstr_standard"
BODY_TYPE"PLUMBING"
HDL_TAP"TRUE";
"B \NAC \NWC"6;
"S \NAC"
BN"4"158;
%"TAP"
"1","(-7750,3375)","2","mstr_standard","I371";
;
CDS_LIB"mstr_standard"
BODY_TYPE"PLUMBING"
HDL_TAP"TRUE";
"B \NAC \NWC"6;
"S \NAC"
BN"3"180;
%"TAP"
"1","(-7750,3225)","2","mstr_standard","I372";
;
CDS_LIB"mstr_standard"
BODY_TYPE"PLUMBING"
HDL_TAP"TRUE";
"B \NAC \NWC"6;
"S \NAC"
BN"0"157;
%"TAP"
"1","(-7750,3275)","2","mstr_standard","I373";
;
CDS_LIB"mstr_standard"
BODY_TYPE"PLUMBING"
HDL_TAP"TRUE";
"B \NAC \NWC"6;
"S \NAC"
BN"1"63;
%"TAP"
"1","(-7750,3325)","2","mstr_standard","I374";
;
CDS_LIB"mstr_standard"
BODY_TYPE"PLUMBING"
HDL_TAP"TRUE";
"B \NAC \NWC"6;
"S \NAC"
BN"2"59;
%"TAP"
"1","(-6050,2275)","0","mstr_standard","I383";
;
CDS_LIB"mstr_standard"
BODY_TYPE"PLUMBING"
HDL_TAP"TRUE";
"B \NAC \NWC"8;
"S \NAC"
BN"1"121;
%"TAP"
"1","(-6050,2225)","0","mstr_standard","I384";
;
CDS_LIB"mstr_standard"
BODY_TYPE"PLUMBING"
HDL_TAP"TRUE";
"B \NAC \NWC"8;
"S \NAC"
BN"0"44;
%"TAP"
"1","(-6050,2325)","0","mstr_standard","I385";
;
CDS_LIB"mstr_standard"
BODY_TYPE"PLUMBING"
HDL_TAP"TRUE";
"B \NAC \NWC"8;
"S \NAC"
BN"2"56;
%"TAP"
"1","(-6050,2375)","0","mstr_standard","I386";
;
CDS_LIB"mstr_standard"
BODY_TYPE"PLUMBING"
HDL_TAP"TRUE";
"B \NAC \NWC"8;
"S \NAC"
BN"3"43;
%"TAP"
"1","(-6050,2425)","0","mstr_standard","I387";
;
CDS_LIB"mstr_standard"
BODY_TYPE"PLUMBING"
HDL_TAP"TRUE";
"B \NAC \NWC"8;
"S \NAC"
BN"4"42;
%"TAP"
"1","(-6050,2475)","0","mstr_standard","I388";
;
CDS_LIB"mstr_standard"
BODY_TYPE"PLUMBING"
HDL_TAP"TRUE";
"B \NAC \NWC"8;
"S \NAC"
BN"5"122;
%"TAP"
"1","(-6050,2525)","0","mstr_standard","I389";
;
CDS_LIB"mstr_standard"
BODY_TYPE"PLUMBING"
HDL_TAP"TRUE";
"B \NAC \NWC"8;
"S \NAC"
BN"6"123;
%"TAP"
"1","(-6050,2575)","0","mstr_standard","I390";
;
CDS_LIB"mstr_standard"
BODY_TYPE"PLUMBING"
HDL_TAP"TRUE";
"B \NAC \NWC"8;
"S \NAC"
BN"7"124;
%"TAP"
"1","(-6050,2625)","0","mstr_standard","I391";
;
CDS_LIB"mstr_standard"
BODY_TYPE"PLUMBING"
HDL_TAP"TRUE";
"B \NAC \NWC"8;
"S \NAC"
BN"8"125;
%"TAP"
"1","(-6050,2675)","0","mstr_standard","I392";
;
CDS_LIB"mstr_standard"
BODY_TYPE"PLUMBING"
HDL_TAP"TRUE";
"B \NAC \NWC"8;
"S \NAC"
BN"9"126;
%"TAP"
"1","(-6050,2725)","0","mstr_standard","I393";
;
CDS_LIB"mstr_standard"
BODY_TYPE"PLUMBING"
HDL_TAP"TRUE";
"B \NAC \NWC"8;
"S \NAC"
BN"10"127;
%"TAP"
"1","(-6050,2825)","0","mstr_standard","I394";
;
CDS_LIB"mstr_standard"
BODY_TYPE"PLUMBING"
HDL_TAP"TRUE";
"B \NAC \NWC"8;
"S \NAC"
BN"12"129;
%"TAP"
"1","(-6050,2775)","0","mstr_standard","I395";
;
CDS_LIB"mstr_standard"
BODY_TYPE"PLUMBING"
HDL_TAP"TRUE";
"B \NAC \NWC"8;
"S \NAC"
BN"11"128;
%"TAP"
"1","(-6050,2875)","0","mstr_standard","I396";
;
CDS_LIB"mstr_standard"
BODY_TYPE"PLUMBING"
HDL_TAP"TRUE";
"B \NAC \NWC"8;
"S \NAC"
BN"13"57;
%"TAP"
"1","(-6050,2975)","0","mstr_standard","I397";
;
CDS_LIB"mstr_standard"
BODY_TYPE"PLUMBING"
HDL_TAP"TRUE";
"B \NAC \NWC"8;
"S \NAC"
BN"15"131;
%"TAP"
"1","(-6050,2925)","0","mstr_standard","I398";
;
CDS_LIB"mstr_standard"
BODY_TYPE"PLUMBING"
HDL_TAP"TRUE";
"B \NAC \NWC"8;
"S \NAC"
BN"14"130;
%"TAP"
"1","(-6050,3025)","0","mstr_standard","I399";
;
CDS_LIB"mstr_standard"
BODY_TYPE"PLUMBING"
HDL_TAP"TRUE";
"B \NAC \NWC"8;
"S \NAC"
BN"16"132;
%"TAP"
"1","(-6050,3075)","0","mstr_standard","I400";
;
CDS_LIB"mstr_standard"
BODY_TYPE"PLUMBING"
HDL_TAP"TRUE";
"B \NAC \NWC"8;
"S \NAC"
BN"17"133;
%"TAP"
"1","(-6050,3125)","0","mstr_standard","I401";
;
CDS_LIB"mstr_standard"
BODY_TYPE"PLUMBING"
HDL_TAP"TRUE";
"B \NAC \NWC"8;
"S \NAC"
BN"18"168;
%"TAP"
"1","(-6050,3175)","0","mstr_standard","I402";
;
CDS_LIB"mstr_standard"
BODY_TYPE"PLUMBING"
HDL_TAP"TRUE";
"B \NAC \NWC"8;
"S \NAC"
BN"19"167;
%"TAP"
"1","(-6050,3375)","0","mstr_standard","I403";
;
CDS_LIB"mstr_standard"
BODY_TYPE"PLUMBING"
HDL_TAP"TRUE";
"B \NAC \NWC"8;
"S \NAC"
BN"23"137;
%"TAP"
"1","(-6050,3225)","0","mstr_standard","I404";
;
CDS_LIB"mstr_standard"
BODY_TYPE"PLUMBING"
HDL_TAP"TRUE";
"B \NAC \NWC"8;
"S \NAC"
BN"20"134;
%"TAP"
"1","(-6050,3275)","0","mstr_standard","I405";
;
CDS_LIB"mstr_standard"
BODY_TYPE"PLUMBING"
HDL_TAP"TRUE";
"B \NAC \NWC"8;
"S \NAC"
BN"21"135;
%"TAP"
"1","(-6050,3325)","0","mstr_standard","I406";
;
CDS_LIB"mstr_standard"
BODY_TYPE"PLUMBING"
HDL_TAP"TRUE";
"B \NAC \NWC"8;
"S \NAC"
BN"22"136;
%"TAP"
"1","(-6050,3425)","0","mstr_standard","I407";
;
CDS_LIB"mstr_standard"
BODY_TYPE"PLUMBING"
HDL_TAP"TRUE";
"B \NAC \NWC"8;
"S \NAC"
BN"24"138;
%"TAP"
"1","(-6050,3625)","0","mstr_standard","I408";
;
CDS_LIB"mstr_standard"
BODY_TYPE"PLUMBING"
HDL_TAP"TRUE";
"B \NAC \NWC"8;
"S \NAC"
BN"28"141;
%"TAP"
"1","(-6050,3475)","0","mstr_standard","I409";
;
CDS_LIB"mstr_standard"
BODY_TYPE"PLUMBING"
HDL_TAP"TRUE";
"B \NAC \NWC"8;
"S \NAC"
BN"25"54;
%"TAP"
"1","(-6050,3525)","0","mstr_standard","I410";
;
CDS_LIB"mstr_standard"
BODY_TYPE"PLUMBING"
HDL_TAP"TRUE";
"B \NAC \NWC"8;
"S \NAC"
BN"26"139;
%"TAP"
"1","(-6050,3575)","0","mstr_standard","I411";
;
CDS_LIB"mstr_standard"
BODY_TYPE"PLUMBING"
HDL_TAP"TRUE";
"B \NAC \NWC"8;
"S \NAC"
BN"27"140;
%"TAP"
"1","(-6050,3675)","0","mstr_standard","I412";
;
CDS_LIB"mstr_standard"
BODY_TYPE"PLUMBING"
HDL_TAP"TRUE";
"B \NAC \NWC"8;
"S \NAC"
BN"29"142;
%"TAP"
"1","(-6050,3875)","0","mstr_standard","I413";
;
CDS_LIB"mstr_standard"
BODY_TYPE"PLUMBING"
HDL_TAP"TRUE";
"B \NAC \NWC"11;
"S \NAC"
BN"0"52;
%"TAP"
"1","(-6050,3725)","0","mstr_standard","I414";
;
CDS_LIB"mstr_standard"
BODY_TYPE"PLUMBING"
HDL_TAP"TRUE";
"B \NAC \NWC"8;
"S \NAC"
BN"30"53;
%"TAP"
"1","(-6050,3775)","0","mstr_standard","I415";
;
CDS_LIB"mstr_standard"
BODY_TYPE"PLUMBING"
HDL_TAP"TRUE";
"B \NAC \NWC"8;
"S \NAC"
BN"31"143;
%"TAP"
"1","(-6050,3975)","0","mstr_standard","I416";
;
CDS_LIB"mstr_standard"
BODY_TYPE"PLUMBING"
HDL_TAP"TRUE";
"B \NAC \NWC"11;
"S \NAC"
BN"2"145;
%"TAP"
"1","(-6050,3925)","0","mstr_standard","I417";
;
CDS_LIB"mstr_standard"
BODY_TYPE"PLUMBING"
HDL_TAP"TRUE";
"B \NAC \NWC"11;
"S \NAC"
BN"1"144;
%"TAP"
"1","(-6050,4025)","0","mstr_standard","I418";
;
CDS_LIB"mstr_standard"
BODY_TYPE"PLUMBING"
HDL_TAP"TRUE";
"B \NAC \NWC"11;
"S \NAC"
BN"3"55;
%"TAP"
"1","(-6050,4125)","0","mstr_standard","I419";
;
CDS_LIB"mstr_standard"
BODY_TYPE"PLUMBING"
HDL_TAP"TRUE";
"B \NAC \NWC"11;
"S \NAC"
BN"5"147;
%"TAP"
"1","(-6050,4075)","0","mstr_standard","I420";
;
CDS_LIB"mstr_standard"
BODY_TYPE"PLUMBING"
HDL_TAP"TRUE";
"B \NAC \NWC"11;
"S \NAC"
BN"4"146;
%"TAP"
"1","(-6050,4225)","0","mstr_standard","I421";
;
CDS_LIB"mstr_standard"
BODY_TYPE"PLUMBING"
HDL_TAP"TRUE";
"B \NAC \NWC"11;
"S \NAC"
BN"7"149;
%"TAP"
"1","(-6050,4175)","0","mstr_standard","I422";
;
CDS_LIB"mstr_standard"
BODY_TYPE"PLUMBING"
HDL_TAP"TRUE";
"B \NAC \NWC"11;
"S \NAC"
BN"6"148;
%"TAP"
"1","(-6050,4275)","0","mstr_standard","I423";
;
CDS_LIB"mstr_standard"
BODY_TYPE"PLUMBING"
HDL_TAP"TRUE";
"B \NAC \NWC"11;
"S \NAC"
BN"8"150;
%"TAP"
"1","(-6050,4375)","0","mstr_standard","I424";
;
CDS_LIB"mstr_standard"
BODY_TYPE"PLUMBING"
HDL_TAP"TRUE";
"B \NAC \NWC"11;
"S \NAC"
BN"10"38;
%"TAP"
"1","(-6050,4325)","0","mstr_standard","I425";
;
CDS_LIB"mstr_standard"
BODY_TYPE"PLUMBING"
HDL_TAP"TRUE";
"B \NAC \NWC"11;
"S \NAC"
BN"9"37;
%"TAP"
"1","(-6050,4425)","0","mstr_standard","I426";
;
CDS_LIB"mstr_standard"
BODY_TYPE"PLUMBING"
HDL_TAP"TRUE";
"B \NAC \NWC"11;
"S \NAC"
BN"11"39;
%"TAP"
"1","(-6050,4475)","0","mstr_standard","I427";
;
CDS_LIB"mstr_standard"
BODY_TYPE"PLUMBING"
HDL_TAP"TRUE";
"B \NAC \NWC"11;
"S \NAC"
BN"12"151;
%"TAP"
"1","(-6050,4525)","0","mstr_standard","I428";
;
CDS_LIB"mstr_standard"
BODY_TYPE"PLUMBING"
HDL_TAP"TRUE";
"B \NAC \NWC"11;
"S \NAC"
BN"13"40;
%"TAP"
"1","(-6050,4575)","0","mstr_standard","I429";
;
CDS_LIB"mstr_standard"
BODY_TYPE"PLUMBING"
HDL_TAP"TRUE";
"B \NAC \NWC"11;
"S \NAC"
BN"14"71;
%"TAP"
"1","(-6050,4625)","0","mstr_standard","I430";
;
CDS_LIB"mstr_standard"
BODY_TYPE"PLUMBING"
HDL_TAP"TRUE";
"B \NAC \NWC"11;
"S \NAC"
BN"15"72;
%"TAP"
"1","(-6050,4825)","0","mstr_standard","I431";
;
CDS_LIB"mstr_standard"
BODY_TYPE"PLUMBING"
HDL_TAP"TRUE";
"B \NAC \NWC"11;
"S \NAC"
BN"19"153;
%"TAP"
"1","(-6050,4875)","0","mstr_standard","I432";
;
CDS_LIB"mstr_standard"
BODY_TYPE"PLUMBING"
HDL_TAP"TRUE";
"B \NAC \NWC"11;
"S \NAC"
BN"20"73;
%"TAP"
"1","(-6050,4675)","0","mstr_standard","I433";
;
CDS_LIB"mstr_standard"
BODY_TYPE"PLUMBING"
HDL_TAP"TRUE";
"B \NAC \NWC"11;
"S \NAC"
BN"16"88;
%"TAP"
"1","(-6050,4725)","0","mstr_standard","I434";
;
CDS_LIB"mstr_standard"
BODY_TYPE"PLUMBING"
HDL_TAP"TRUE";
"B \NAC \NWC"11;
"S \NAC"
BN"17"61;
%"TAP"
"1","(-6050,4775)","0","mstr_standard","I435";
;
CDS_LIB"mstr_standard"
BODY_TYPE"PLUMBING"
HDL_TAP"TRUE";
"B \NAC \NWC"11;
"S \NAC"
BN"18"152;
%"TAP"
"1","(-6050,5025)","0","mstr_standard","I437";
;
CDS_LIB"mstr_standard"
BODY_TYPE"PLUMBING"
HDL_TAP"TRUE";
"B \NAC \NWC"11;
"S \NAC"
BN"23"156;
%"TAP"
"1","(-6050,4925)","0","mstr_standard","I438";
;
CDS_LIB"mstr_standard"
BODY_TYPE"PLUMBING"
HDL_TAP"TRUE";
"B \NAC \NWC"11;
"S \NAC"
BN"21"154;
%"TAP"
"1","(-6050,4975)","0","mstr_standard","I439";
;
CDS_LIB"mstr_standard"
BODY_TYPE"PLUMBING"
HDL_TAP"TRUE";
"B \NAC \NWC"11;
"S \NAC"
BN"22"155;
%"TAP"
"1","(-6050,5175)","0","mstr_standard","I440";
;
CDS_LIB"mstr_standard"
BODY_TYPE"PLUMBING"
HDL_TAP"TRUE";
"B \NAC \NWC"11;
"S \NAC"
BN"26"76;
%"TAP"
"1","(-6050,5125)","0","mstr_standard","I441";
;
CDS_LIB"mstr_standard"
BODY_TYPE"PLUMBING"
HDL_TAP"TRUE";
"B \NAC \NWC"11;
"S \NAC"
BN"25"75;
%"TAP"
"1","(-6050,5075)","0","mstr_standard","I442";
;
CDS_LIB"mstr_standard"
BODY_TYPE"PLUMBING"
HDL_TAP"TRUE";
"B \NAC \NWC"11;
"S \NAC"
BN"24"74;
%"TAP"
"1","(-6050,5325)","0","mstr_standard","I443";
;
CDS_LIB"mstr_standard"
BODY_TYPE"PLUMBING"
HDL_TAP"TRUE";
"B \NAC \NWC"11;
"S \NAC"
BN"29"79;
%"TAP"
"1","(-6050,5375)","0","mstr_standard","I444";
;
CDS_LIB"mstr_standard"
BODY_TYPE"PLUMBING"
HDL_TAP"TRUE";
"B \NAC \NWC"11;
"S \NAC"
BN"30"95;
%"TAP"
"1","(-6050,5425)","0","mstr_standard","I445";
;
CDS_LIB"mstr_standard"
BODY_TYPE"PLUMBING"
HDL_TAP"TRUE";
"B \NAC \NWC"11;
"S \NAC"
BN"31"91;
%"TAP"
"1","(-6050,5225)","0","mstr_standard","I446";
;
CDS_LIB"mstr_standard"
BODY_TYPE"PLUMBING"
HDL_TAP"TRUE";
"B \NAC \NWC"11;
"S \NAC"
BN"27"77;
%"TAP"
"1","(-6050,5275)","0","mstr_standard","I447";
;
CDS_LIB"mstr_standard"
BODY_TYPE"PLUMBING"
HDL_TAP"TRUE";
"B \NAC \NWC"11;
"S \NAC"
BN"28"78;
%"TAP"
"1","(-3600,3425)","0","mstr_standard","I449";
;
CDS_LIB"mstr_standard"
BODY_TYPE"PLUMBING"
HDL_TAP"TRUE";
"B \NAC \NWC"12;
"S \NAC"
BN"0"115;
%"TAP"
"1","(-3600,3525)","0","mstr_standard","I450";
;
CDS_LIB"mstr_standard"
BODY_TYPE"PLUMBING"
HDL_TAP"TRUE";
"B \NAC \NWC"12;
"S \NAC"
BN"1"112;
%"TAP"
"1","(-3400,3575)","0","mstr_standard","I451";
;
CDS_LIB"mstr_standard"
BODY_TYPE"PLUMBING"
HDL_TAP"TRUE";
"B \NAC \NWC"15;
"S \NAC"
BN"2"109;
%"TAP"
"1","(-3400,3475)","0","mstr_standard","I452";
;
CDS_LIB"mstr_standard"
BODY_TYPE"PLUMBING"
HDL_TAP"TRUE";
"B \NAC \NWC"15;
"S \NAC"
BN"1"45;
%"TAP"
"1","(-3400,3375)","0","mstr_standard","I453";
;
CDS_LIB"mstr_standard"
BODY_TYPE"PLUMBING"
HDL_TAP"TRUE";
"B \NAC \NWC"15;
"S \NAC"
BN"0"46;
%"TAP"
"1","(-3600,3625)","0","mstr_standard","I454";
;
CDS_LIB"mstr_standard"
BODY_TYPE"PLUMBING"
HDL_TAP"TRUE";
"B \NAC \NWC"12;
"S \NAC"
BN"2"108;
%"TAP"
"1","(-3600,3725)","0","mstr_standard","I455";
;
CDS_LIB"mstr_standard"
BODY_TYPE"PLUMBING"
HDL_TAP"TRUE";
"B \NAC \NWC"12;
"S \NAC"
BN"3"104;
%"TAP"
"1","(-3600,3825)","0","mstr_standard","I456";
;
CDS_LIB"mstr_standard"
BODY_TYPE"PLUMBING"
HDL_TAP"TRUE";
"B \NAC \NWC"12;
"S \NAC"
BN"4"86;
%"TAP"
"1","(-3400,3675)","0","mstr_standard","I457";
;
CDS_LIB"mstr_standard"
BODY_TYPE"PLUMBING"
HDL_TAP"TRUE";
"B \NAC \NWC"15;
"S \NAC"
BN"3"105;
%"TAP"
"1","(-3400,3775)","0","mstr_standard","I458";
;
CDS_LIB"mstr_standard"
BODY_TYPE"PLUMBING"
HDL_TAP"TRUE";
"B \NAC \NWC"15;
"S \NAC"
BN"4"87;
%"TAP"
"1","(-3600,3925)","0","mstr_standard","I459";
;
CDS_LIB"mstr_standard"
BODY_TYPE"PLUMBING"
HDL_TAP"TRUE";
"B \NAC \NWC"12;
"S \NAC"
BN"5"99;
%"TAP"
"1","(-3600,4025)","0","mstr_standard","I460";
;
CDS_LIB"mstr_standard"
BODY_TYPE"PLUMBING"
HDL_TAP"TRUE";
"B \NAC \NWC"12;
"S \NAC"
BN"6"83;
%"TAP"
"1","(-3400,4075)","0","mstr_standard","I461";
;
CDS_LIB"mstr_standard"
BODY_TYPE"PLUMBING"
HDL_TAP"TRUE";
"B \NAC \NWC"15;
"S \NAC"
BN"7"82;
%"TAP"
"1","(-3400,3975)","0","mstr_standard","I462";
;
CDS_LIB"mstr_standard"
BODY_TYPE"PLUMBING"
HDL_TAP"TRUE";
"B \NAC \NWC"15;
"S \NAC"
BN"6"84;
%"TAP"
"1","(-3400,3875)","0","mstr_standard","I463";
;
CDS_LIB"mstr_standard"
BODY_TYPE"PLUMBING"
HDL_TAP"TRUE";
"B \NAC \NWC"15;
"S \NAC"
BN"5"85;
%"TAP"
"1","(-3600,4125)","0","mstr_standard","I464";
;
CDS_LIB"mstr_standard"
BODY_TYPE"PLUMBING"
HDL_TAP"TRUE";
"B \NAC \NWC"12;
"S \NAC"
BN"7"81;
%"TAP"
"1","(-3600,4225)","0","mstr_standard","I465";
;
CDS_LIB"mstr_standard"
BODY_TYPE"PLUMBING"
HDL_TAP"TRUE";
"B \NAC \NWC"12;
"S \NAC"
BN"8"48;
%"TAP"
"1","(-3600,4325)","0","mstr_standard","I466";
;
CDS_LIB"mstr_standard"
BODY_TYPE"PLUMBING"
HDL_TAP"TRUE";
"B \NAC \NWC"12;
"S \NAC"
BN"9"67;
%"TAP"
"1","(-3400,4175)","0","mstr_standard","I467";
;
CDS_LIB"mstr_standard"
BODY_TYPE"PLUMBING"
HDL_TAP"TRUE";
"B \NAC \NWC"15;
"S \NAC"
BN"8"80;
%"TAP"
"1","(-3400,4275)","0","mstr_standard","I468";
;
CDS_LIB"mstr_standard"
BODY_TYPE"PLUMBING"
HDL_TAP"TRUE";
"B \NAC \NWC"15;
"S \NAC"
BN"9"49;
%"TAP"
"1","(-3600,4475)","0","mstr_standard","I469";
;
CDS_LIB"mstr_standard"
BODY_TYPE"PLUMBING"
HDL_TAP"TRUE";
"B \NAC \NWC"14;
"S \NAC"
BN"0"51;
%"TAP"
"1","(-3600,4575)","0","mstr_standard","I470";
;
CDS_LIB"mstr_standard"
BODY_TYPE"PLUMBING"
HDL_TAP"TRUE";
"B \NAC \NWC"14;
"S \NAC"
BN"1"113;
%"TAP"
"1","(-3400,4425)","0","mstr_standard","I471";
;
CDS_LIB"mstr_standard"
BODY_TYPE"PLUMBING"
HDL_TAP"TRUE";
"B \NAC \NWC"13;
"S \NAC"
BN"0"50;
%"TAP"
"1","(-3400,4525)","0","mstr_standard","I472";
;
CDS_LIB"mstr_standard"
BODY_TYPE"PLUMBING"
HDL_TAP"TRUE";
"B \NAC \NWC"13;
"S \NAC"
BN"1"114;
%"TAP"
"1","(-3600,4675)","0","mstr_standard","I473";
;
CDS_LIB"mstr_standard"
BODY_TYPE"PLUMBING"
HDL_TAP"TRUE";
"B \NAC \NWC"14;
"S \NAC"
BN"2"110;
%"TAP"
"1","(-3600,4775)","0","mstr_standard","I474";
;
CDS_LIB"mstr_standard"
BODY_TYPE"PLUMBING"
HDL_TAP"TRUE";
"B \NAC \NWC"14;
"S \NAC"
BN"3"106;
%"TAP"
"1","(-3400,4625)","0","mstr_standard","I475";
;
CDS_LIB"mstr_standard"
BODY_TYPE"PLUMBING"
HDL_TAP"TRUE";
"B \NAC \NWC"13;
"S \NAC"
BN"2"111;
%"TAP"
"1","(-3400,4725)","0","mstr_standard","I476";
;
CDS_LIB"mstr_standard"
BODY_TYPE"PLUMBING"
HDL_TAP"TRUE";
"B \NAC \NWC"13;
"S \NAC"
BN"3"107;
%"TAP"
"1","(-3400,4825)","0","mstr_standard","I477";
;
CDS_LIB"mstr_standard"
BODY_TYPE"PLUMBING"
HDL_TAP"TRUE";
"B \NAC \NWC"13;
"S \NAC"
BN"4"103;
%"TAP"
"1","(-3600,4875)","0","mstr_standard","I480";
;
CDS_LIB"mstr_standard"
BODY_TYPE"PLUMBING"
HDL_TAP"TRUE";
"B \NAC \NWC"14;
"S \NAC"
BN"4"102;
%"TAP"
"1","(-3600,4975)","0","mstr_standard","I481";
;
CDS_LIB"mstr_standard"
BODY_TYPE"PLUMBING"
HDL_TAP"TRUE";
"B \NAC \NWC"14;
"S \NAC"
BN"5"100;
%"TAP"
"1","(-3600,5075)","0","mstr_standard","I482";
;
CDS_LIB"mstr_standard"
BODY_TYPE"PLUMBING"
HDL_TAP"TRUE";
"B \NAC \NWC"14;
"S \NAC"
BN"6"69;
%"TAP"
"1","(-3400,5125)","0","mstr_standard","I483";
;
CDS_LIB"mstr_standard"
BODY_TYPE"PLUMBING"
HDL_TAP"TRUE";
"B \NAC \NWC"13;
"S \NAC"
BN"7"70;
%"TAP"
"1","(-3400,5025)","0","mstr_standard","I484";
;
CDS_LIB"mstr_standard"
BODY_TYPE"PLUMBING"
HDL_TAP"TRUE";
"B \NAC \NWC"13;
"S \NAC"
BN"6"68;
%"TAP"
"1","(-3400,4925)","0","mstr_standard","I485";
;
CDS_LIB"mstr_standard"
BODY_TYPE"PLUMBING"
HDL_TAP"TRUE";
"B \NAC \NWC"13;
"S \NAC"
BN"5"101;
%"TAP"
"1","(-3600,5175)","0","mstr_standard","I486";
;
CDS_LIB"mstr_standard"
BODY_TYPE"PLUMBING"
HDL_TAP"TRUE";
"B \NAC \NWC"14;
"S \NAC"
BN"7"98;
%"TAP"
"1","(-3600,5275)","0","mstr_standard","I487";
;
CDS_LIB"mstr_standard"
BODY_TYPE"PLUMBING"
HDL_TAP"TRUE";
"B \NAC \NWC"14;
"S \NAC"
BN"8"96;
%"TAP"
"1","(-3600,5375)","0","mstr_standard","I488";
;
CDS_LIB"mstr_standard"
BODY_TYPE"PLUMBING"
HDL_TAP"TRUE";
"B \NAC \NWC"14;
"S \NAC"
BN"9"93;
%"TAP"
"1","(-3400,5325)","0","mstr_standard","I489";
;
CDS_LIB"mstr_standard"
BODY_TYPE"PLUMBING"
HDL_TAP"TRUE";
"B \NAC \NWC"13;
"S \NAC"
BN"9"94;
%"TAP"
"1","(-3400,5225)","0","mstr_standard","I490";
;
CDS_LIB"mstr_standard"
BODY_TYPE"PLUMBING"
HDL_TAP"TRUE";
"B \NAC \NWC"13;
"S \NAC"
BN"8"97;
%"VCC_CORE"
"1","(-8875,3525)","0","mstr_symbols","I493";
;
HDL_POWER"P3V3_AUX"
ROOM"PVCCINFAON_CPU0_CTRL"
VOLTAGE"3.3"
CDS_LIB"mstr_symbols";
"A"20;
%"GND"
"1","(-6500,1100)","0","mstr_symbols","I498";
;
VOLTAGE"0.0"
SIZE"1B"
CDS_LIB"mstr_symbols"
BOM_COST"MEM"
BODY_TYPE"PLUMBING"
HDL_POWER"GND";
"A\NAC"1;
%"Q_RES"
"2","(-6500,1325)","0","pure_quanta","I499";
;
LOCATION"R7"
SEC"1"
TOLERANCE"1%"
VALUE"10K"
PACK_TYPE"0402LF"
WATTAGE"1/16W"
MATERIAL"CHIP"
ROOM""
CDS_LIB"pure_quanta"
SEC_TYPE"0402LF"
BOM_COST"MEM"
PART_NUMBER"CS31002FB08";
"A"
$PN"1"
XNET_PINS"3"169;
"B"
$PN"2"
XNET_PINS"2"1;
%"Q_CAP"
"1","(-2950,6050)","2","pure_quanta","I519";
;
LOCATION"C89"
$SEC"1"
CDS_SEC"1"
TOLERANCE"10%"
VALUE"10UF"
VOLTAGE"25V"
PACK_TYPE"C0805"
MATERIAL"X6S"
ROOM""
CDS_LIB"pure_quanta"
BOM_COST"MEM"
PART_NUMBER"CH6104KEA00";
"B"
$PN"2"27;
"A"
$PN"1"28;
%"GND"
"1","(-2950,5700)","0","mstr_symbols","I522";
;
ROOM"MEM_EFGH_DECOUPLING_CAPS"
VOLTAGE"0"
CDS_LIB"mstr_symbols"
SIZE"1B"
BOM_COST"MEM"
BODY_TYPE"PLUMBING"
HDL_POWER"GND";
"A\NAC"27;
%"Q_CAP"
"1","(-9000,3225)","2","pure_quanta","I523";
;
LOCATION"C88"
$SEC"1"
CDS_SEC"1"
MATERIAL"X7R"
TOLERANCE"10%"
PACK_TYPE"0402"
VOLTAGE"25V"
VALUE"0.1UF"
CDS_LIB"pure_quanta"
BOM_COST"MEM"
PART_NUMBER"CH4104K1B00";
"B"
$PN"2"2;
"A"
$PN"1"20;
%"GND"
"1","(-9000,3000)","0","mstr_symbols","I524";
;
ROOM"MEM_EFGH_DECOUPLING_CAPS"
VOLTAGE"0"
CDS_LIB"mstr_symbols"
SIZE"1B"
BOM_COST"MEM"
BODY_TYPE"PLUMBING"
HDL_POWER"GND";
"A\NAC"2;
%"Q_RES"
"1","(-8575,2250)","2","pure_quanta","I525";
;
LOCATION"R291"
$SEC"1"
CDS_SEC"1"
VALUE"1K"
PACK_TYPE"0402LF"
MATERIAL"CHIP"
WATTAGE"1/16W"
CDS_LIB"pure_quanta"
BOM_COST"MEM"
TOLERANCE"1%"
ROOM""
PART_NUMBER"CS21002FB06";
"B"
$PN"2"172;
"A"
$PN"1"33;
%"Q_RES"
"2","(-8700,2400)","2","pure_quanta","I526";
;
LOCATION"R88"
$SEC"1"
CDS_SEC"1"
TOLERANCE"1%"
WATTAGE"1/16W"
MATERIAL"EMPTY"
PACK_TYPE"0402LF"
VALUE"1K"
ROOM""
BOM_COST"MEM"
CDS_LIB"pure_quanta"
PART_NUMBER"CS21002FB06";
"A"
$PN"1"3;
"B"
$PN"2"172;
%"VCC_CORE"
"1","(-8700,2575)","0","mstr_symbols","I527";
;
HDL_POWER"P3V3"
VOLTAGE"3.3"
ROOM"PVCCINFAON_CPU0_CTRL"
CDS_LIB"mstr_symbols";
"A"3;
%"Q_RES"
"2","(-8450,2400)","0","pure_quanta","I528";
;
LOCATION"R89"
$SEC"1"
CDS_SEC"1"
WATTAGE"1/16W"
MATERIAL"EMPTY"
PACK_TYPE"0402LF"
TOLERANCE"1%"
VALUE"1K"
ROOM""
BOM_COST"MEM"
CDS_LIB"pure_quanta"
PART_NUMBER"CS21002FB06";
"A"
$PN"1"4;
"B"
$PN"2"33;
%"VCC_CORE"
"1","(-8450,2575)","0","mstr_symbols","I529";
;
HDL_POWER"P3V3"
ROOM"PVCCINFAON_CPU0_CTRL"
VOLTAGE"3.3"
CDS_LIB"mstr_symbols";
"A"4;
%"Q_CAP"
"1","(-2375,6050)","2","pure_quanta","I534";
;
LOCATION"C142"
$SEC"1"
CDS_SEC"1"
MATERIAL"X6S"
VOLTAGE"25V"
PACK_TYPE"C0805"
VALUE"10UF"
TOLERANCE"10%"
ROOM""
CDS_LIB"pure_quanta"
BOM_COST"MEM"
PART_NUMBER"CH6104KEA00";
"B"
$PN"2"27;
"A"
$PN"1"28;
%"UNIVERSAL_POWER"
"1","(-2950,6375)","0","pure_quanta_power","I535";
;
HDL_POWER"P12V_MEM_CPU0"
CDS_LIB"pure_quanta_power"
BOM_COST"VR_SYSTEM";
"A"28;
%"SCONN288_DDR506112002KQ"
"1","(-6900,3675)","0","pure_quanta","I536";
;
LOCATION"J1"
$SEC"1"
CDS_SEC"1"
VALUE"SCONN288_DDR506112002KQ"
PART_TYPE"SMLF"
MATERIAL"IO"
CDS_LIB"pure_quanta"
CDS_LMAN_SYM_OUTLINE"-450,1900,450,-1850"
NEEDS_NO_SIZE"TRUE"
PART_NUMBER"DFHST8FS479";
"PWR_GOOD||FAIL_N"
$PN"147"33;
"DQ31_A"
$PN"194"91;
"CB7_A"
$PN"205"166;
"CB4_A"
$PN"58"66;
"CB1_A"
$PN"53"35;
"CB7_B"
$PN"236"177;
"ALERT_N \B"
$PN"62"16;
"CA0_A"
$PN"66"62;
"CA0_B"
$PN"76"165;
"CA1_A"
$PN"211"164;
"CA1_B"
$PN"221"117;
"CA2_A"
$PN"68"163;
"CA2_B"
$PN"78"58;
"CA3_A"
$PN"213"60;
"CA3_B"
$PN"223"162;
"CA4_A"
$PN"70"119;
"CA4_B"
$PN"80"118;
"CA5_A"
$PN"215"116;
"CA5_B"
$PN"225"92;
"CA6_A"
$PN"72"90;
"CA6_B"
$PN"82"161;
"CB6_A"
$PN"203"160;
"CB5_A"
$PN"60"23;
"CB3_A"
$PN"198"65;
"CB2_A"
$PN"196"36;
"CB0_A"
$PN"51"176;
"CB6_B"
$PN"234"47;
"CB5_B"
$PN"91"159;
"CB4_B"
$PN"89"158;
"CB3_B"
$PN"243"180;
"CB2_B"
$PN"241"59;
"CB1_B"
$PN"98"63;
"CB0_B"
$PN"96"157;
"CK_C \B"
$PN"218"21;
"CK_T"
$PN"217"24;
"CS0_A_N"
$PN"64"178;
"CS0_B_N"
$PN"84"22;
"CS1_A_N"
$PN"209"89;
"CS1_B_N"
$PN"229"179;
"DQ30_A"
$PN"192"95;
"DQ29_A"
$PN"49"79;
"DQ28_A"
$PN"47"78;
"DQ27_A"
$PN"187"77;
"DQ26_A"
$PN"185"76;
"DQ25_A"
$PN"42"75;
"DQ24_A"
$PN"40"74;
"DQ23_A"
$PN"183"156;
"DQ22_A"
$PN"181"155;
"DQ21_A"
$PN"38"154;
"DQ20_A"
$PN"36"73;
"DQ19_A"
$PN"176"153;
"DQ18_A"
$PN"174"152;
"DQ17_A"
$PN"31"61;
"DQ16_A"
$PN"29"88;
"DQ15_A"
$PN"172"72;
"DQ14_A"
$PN"170"71;
"DQ13_A"
$PN"27"40;
"DQ12_A"
$PN"25"151;
"DQ11_A"
$PN"165"39;
"DQ10_A"
$PN"163"38;
"DQ9_A"
$PN"20"37;
"DQ8_A"
$PN"18"150;
"DQ7_A"
$PN"161"149;
"DQ6_A"
$PN"159"148;
"DQ5_A"
$PN"16"147;
"DQ4_A"
$PN"14"146;
"DQ3_A"
$PN"154"55;
"DQ2_A"
$PN"152"145;
"DQ1_A"
$PN"9"144;
"DQ0_A"
$PN"7"52;
"DQ31_B"
$PN"287"143;
"DQ30_B"
$PN"285"53;
"DQ29_B"
$PN"142"142;
"DQ28_B"
$PN"140"141;
"DQ27_B"
$PN"280"140;
"DQ26_B"
$PN"278"139;
"DQ25_B"
$PN"135"54;
"DQ24_B"
$PN"133"138;
"DQ23_B"
$PN"276"137;
"DQ22_B"
$PN"274"136;
"DQ21_B"
$PN"131"135;
"DQ20_B"
$PN"129"134;
"DQ19_B"
$PN"269"167;
"DQ18_B"
$PN"267"168;
"DQ17_B"
$PN"124"133;
"DQ16_B"
$PN"122"132;
"DQ15_B"
$PN"265"131;
"DQ14_B"
$PN"263"130;
"DQ13_B"
$PN"120"57;
"DQ12_B"
$PN"118"129;
"DQ11_B"
$PN"258"128;
"DQ10_B"
$PN"256"127;
"DQ9_B"
$PN"113"126;
"DQ8_B"
$PN"111"125;
"DQ7_B"
$PN"254"124;
"DQ6_B"
$PN"252"123;
"DQ5_B"
$PN"109"122;
"DQ4_B"
$PN"107"42;
"DQ3_B"
$PN"247"43;
"DQ2_B"
$PN"245"56;
"DQ1_B"
$PN"102"121;
"DQ0_B"
$PN"100"44;
"HAS"
$PN"148"19;
"HSCL"
$PN"4"32;
"HSDA"
$PN"5"31;
"LBD||RSP_A_N"
$PN"86"175;
"LBS||RSP_B_N"
$PN"87"41;
"PAR_A"
$PN"74"120;
"PAR_B"
$PN"227"64;
"RESET_N \B"
$PN"207"34;
"RFU6"
$PN"232"0;
"RFU5"
$PN"231"0;
"RFU4"
$PN"220"0;
"RFU3"
$PN"150"0;
"RFU2"
$PN"149"0;
"RFU1"
$PN"144"0;
"RFU0"
$PN"2"0;
"VIN_MGMT"
$PN"3"20;
%"SCONN288_DDR506112002KQ"
"2","(-4600,4375)","0","pure_quanta","I537";
;
LOCATION"J1"
$SEC"2"
CDS_SEC"2"
PART_TYPE"SMLF"
VALUE"SCONN288_DDR506112002KQ"
MATERIAL"IO"
CDS_LIB"pure_quanta"
CDS_LMAN_SYM_OUTLINE"-600,1150,600,-1150"
NEEDS_NO_SIZE"TRUE"
PART_NUMBER"DFHST8FS479";
"DQS7_A_C||TDQS7_A_C \B"
$PN"178"70;
"DQS6_A_T||TDQS6_A_T"
$PN"168"69;
"DQS8_B_T||TDQS8_B_T"
$PN"283"48;
"DQS8_B_C||TDQS8_B_C \B"
$PN"282"80;
"DQS7_B_T||TDQS7_B_T"
$PN"272"81;
"DQS0_A_C \B"
$PN"12"50;
"DQS0_A_T"
$PN"11"51;
"DQS0_B_C \B"
$PN"105"46;
"DQS0_B_T"
$PN"104"115;
"DQS1_A_C \B"
$PN"23"114;
"DQS1_A_T"
$PN"22"113;
"DQS1_B_C \B"
$PN"116"45;
"DQS1_B_T"
$PN"115"112;
"DQS2_A_C \B"
$PN"34"111;
"DQS2_A_T"
$PN"33"110;
"DQS2_B_C \B"
$PN"127"109;
"DQS2_B_T"
$PN"126"108;
"DQS3_A_C \B"
$PN"45"107;
"DQS3_A_T"
$PN"44"106;
"DQS3_B_C \B"
$PN"138"105;
"DQS3_B_T"
$PN"137"104;
"DQS4_A_C \B"
$PN"56"103;
"DQS4_A_T"
$PN"55"102;
"DQS4_B_C \B"
$PN"238"87;
"DQS4_B_T"
$PN"239"86;
"DQS5_A_C||TDQS5_A_C||DQS5_A_T||TDQS5_A_T \B"
$PN"156"101;
"DQS5_A_T||TDQS5_A_T"
$PN"157"100;
"DQS5_B_C||TDQS5_B_C \B"
$PN"249"85;
"DQS5_B_T||TDQS5_B_T"
$PN"250"99;
"DQS6_A_C||TDQS6_A_C||DQS6_A_T||TDQS6_A_T \B"
$PN"167"68;
"DQS6_B_C||TDQS6_B_C \B"
$PN"260"84;
"DQS6_B_T||TDQS6_B_T"
$PN"261"83;
"DQS7_A_T||TDQS7_A_T"
$PN"179"98;
"DQS7_B_C||TDQS7_B_C \B"
$PN"271"82;
"DQS8_A_C||TDQS8_A_C \B"
$PN"189"97;
"DQS8_A_T||TDQS8_A_T"
$PN"190"96;
"DQS9_A_C||TDQS9_A_C \B"
$PN"200"94;
"DQS9_A_T||TDQS9_A_T"
$PN"201"93;
"DQS9_B_C||TDQS9_B_C \B"
$PN"94"49;
"DQS9_B_T||TDQS9_B_T||DBI4_B_N"
$PN"93"67;
%"SCONN288_DDR506112002KQ"
"3","(-1450,3700)","0","pure_quanta","I538";
;
LOCATION"J1"
$SEC"3"
CDS_SEC"3"
VALUE"SCONN288_DDR506112002KQ"
MATERIAL"IO"
PART_TYPE"SMLF"
CDS_LIB"pure_quanta"
CDS_LMAN_SYM_OUTLINE"-450,1800,450,-1750"
NEEDS_NO_SIZE"TRUE"
PART_NUMBER"DFHST8FS479";
"G3"
$PN"G3"25;
"G2"
$PN"G2"25;
"G1"
$PN"G1"25;
"VSS62"
$PN"141"25;
"VSS61"
$PN"139"25;
"VSS60"
$PN"136"25;
"VSS58"
$PN"132"25;
"VSS104"
$PN"240"26;
"VSS102"
$PN"235"26;
"VSS100"
$PN"230"26;
"VIN_BULK2"
$PN"146"28;
"VIN_BULK1"
$PN"145"28;
"VIN_BULK0"
$PN"1"28;
"VSS126"
$PN"288"26;
"VSS125"
$PN"286"26;
"VSS124"
$PN"284"26;
"VSS123"
$PN"281"26;
"VSS122"
$PN"279"26;
"VSS121"
$PN"277"26;
"VSS120"
$PN"275"26;
"VSS119"
$PN"273"26;
"VSS118"
$PN"270"26;
"VSS117"
$PN"268"26;
"VSS116"
$PN"266"26;
"VSS115"
$PN"264"26;
"VSS114"
$PN"262"26;
"VSS113"
$PN"259"26;
"VSS112"
$PN"257"26;
"VSS111"
$PN"255"26;
"VSS110"
$PN"253"26;
"VSS109"
$PN"251"26;
"VSS108"
$PN"248"26;
"VSS107"
$PN"246"26;
"VSS106"
$PN"244"26;
"VSS105"
$PN"242"26;
"VSS103"
$PN"237"26;
"VSS101"
$PN"233"26;
"VSS99"
$PN"228"26;
"VSS98"
$PN"226"26;
"VSS97"
$PN"224"26;
"VSS96"
$PN"222"26;
"VSS95"
$PN"219"26;
"VSS94"
$PN"216"26;
"VSS93"
$PN"214"26;
"VSS92"
$PN"212"26;
"VSS91"
$PN"210"26;
"VSS90"
$PN"208"26;
"VSS89"
$PN"206"26;
"VSS88"
$PN"204"26;
"VSS87"
$PN"202"26;
"VSS86"
$PN"199"26;
"VSS85"
$PN"197"26;
"VSS84"
$PN"195"26;
"VSS83"
$PN"193"26;
"VSS82"
$PN"191"26;
"VSS81"
$PN"188"26;
"VSS80"
$PN"186"26;
"VSS79"
$PN"184"26;
"VSS78"
$PN"182"26;
"VSS77"
$PN"180"26;
"VSS76"
$PN"177"26;
"VSS75"
$PN"175"26;
"VSS74"
$PN"173"26;
"VSS73"
$PN"171"26;
"VSS72"
$PN"169"26;
"VSS71"
$PN"166"26;
"VSS70"
$PN"164"26;
"VSS69"
$PN"162"26;
"VSS68"
$PN"160"26;
"VSS67"
$PN"158"26;
"VSS66"
$PN"155"26;
"VSS65"
$PN"153"26;
"VSS64"
$PN"151"26;
"VSS63"
$PN"143"25;
"VSS59"
$PN"134"25;
"VSS57"
$PN"130"25;
"VSS56"
$PN"128"25;
"VSS55"
$PN"125"25;
"VSS54"
$PN"123"25;
"VSS53"
$PN"121"25;
"VSS52"
$PN"119"25;
"VSS51"
$PN"117"25;
"VSS50"
$PN"114"25;
"VSS49"
$PN"112"25;
"VSS48"
$PN"110"25;
"VSS47"
$PN"108"25;
"VSS46"
$PN"106"25;
"VSS45"
$PN"103"25;
"VSS44"
$PN"101"25;
"VSS43"
$PN"99"25;
"VSS42"
$PN"97"25;
"VSS41"
$PN"95"25;
"VSS40"
$PN"92"25;
"VSS39"
$PN"90"25;
"VSS38"
$PN"88"25;
"VSS37"
$PN"85"25;
"VSS36"
$PN"83"25;
"VSS35"
$PN"81"25;
"VSS34"
$PN"79"25;
"VSS33"
$PN"77"25;
"VSS32"
$PN"75"25;
"VSS31"
$PN"73"25;
"VSS30"
$PN"71"25;
"VSS29"
$PN"69"25;
"VSS28"
$PN"67"25;
"VSS27"
$PN"65"25;
"VSS26"
$PN"63"25;
"VSS25"
$PN"61"25;
"VSS24"
$PN"59"25;
"VSS23"
$PN"57"25;
"VSS22"
$PN"54"25;
"VSS21"
$PN"52"25;
"VSS20"
$PN"50"25;
"VSS19"
$PN"48"25;
"VSS18"
$PN"46"25;
"VSS17"
$PN"43"25;
"VSS16"
$PN"41"25;
"VSS15"
$PN"39"25;
"VSS14"
$PN"37"25;
"VSS13"
$PN"35"25;
"VSS12"
$PN"32"25;
"VSS11"
$PN"30"25;
"VSS10"
$PN"28"25;
"VSS9"
$PN"26"25;
"VSS8"
$PN"24"25;
"VSS7"
$PN"21"25;
"VSS6"
$PN"19"25;
"VSS5"
$PN"17"25;
"VSS4"
$PN"15"25;
"VSS3"
$PN"13"25;
"VSS2"
$PN"10"25;
"VSS1"
$PN"8"25;
"VSS0"
$PN"6"25;
%"Q_RES"
"1","(-7775,2700)","0","pure_quanta","I539";
;
LOCATION"R1568"
$SEC"1"
CDS_SEC"1"
VALUE"49.9"
CDS_LIB"pure_quanta"
MATERIAL"CHIP"
PACK_TYPE"0402LF"
WATTAGE"1/16W"
TOLERANCE"1%"
PART_NUMBER"CS04992FB07";
"B"
$PN"2"32;
"A"
$PN"1"17;
%"Q_RES"
"2","(-8750,1375)","0","pure_quanta","I540";
;
LOCATION"R8037"
$SEC"1"
CDS_SEC"1"
WATTAGE"1/16W"
MATERIAL"CHIP"
VALUE"10K"
TOLERANCE"1%"
PACK_TYPE"0402LF"
CDS_LIB"pure_quanta"
PART_NUMBER"CS31002FB08";
"A"
$PN"1"5;
"B"
$PN"2"173;
%"VCC_CORE"
"1","(-8750,1675)","0","mstr_symbols","I541";
;
HDL_POWER"P3V3_AUX"
CDS_LIB"mstr_symbols"
VOLTAGE"3.3"
ROOM"PVCCINFAON_CPU0_CTRL";
"A"5;
%"Q_RES"
"1","(-4525,900)","0","pure_quanta","I544";
;
LOCATION"R8080"
$SEC"1"
CDS_SEC"1"
PACK_TYPE"0402LF"
MATERIAL"CHIP"
WATTAGE"1/16W"
TOLERANCE"5%"
VALUE"0"
CDS_LIB"pure_quanta"
PART_NUMBER"CS00002JB13";
"B"
$PN"2"170;
"A"
$PN"1"174;
%"Q_RES"
"1","(-3100,900)","0","pure_quanta","I545";
;
LOCATION"R8081"
$SEC"1"
CDS_SEC"1"
MATERIAL"CHIP"
PACK_TYPE"0402LF"
WATTAGE"1/16W"
TOLERANCE"5%"
VALUE"0"
CDS_LIB"pure_quanta"
PART_NUMBER"CS00002JB13";
"B"
$PN"2"171;
"A"
$PN"1"170;
%"Q_RES"
"1","(-4950,1375)","0","pure_quanta","I547";
;
LOCATION"R8082"
$SEC"1"
CDS_SEC"1"
VALUE"10K"
TOLERANCE"1%"
MATERIAL"EMPTY"
PACK_TYPE"0402LF"
WATTAGE"1/16W"
CDS_LIB"pure_quanta"
PART_NUMBER"CS31002FB08";
"B"
$PN"2"170;
"A"
$PN"1"29;
%"VCC_CORE"
"1","(-5550,1575)","0","mstr_symbols","I548";
;
HDL_POWER"P3V3_AUX"
ROOM"PVCCINFAON_CPU0_CTRL"
VOLTAGE"3.3"
CDS_LIB"mstr_symbols";
"A"29;
%"SCHOTTKY_12"
"1","(-3000,1350)","0","pure_quanta","I549";
;
LOCATION"D8003"
SEC"1"
VALUE"B0530WS7F"
PART_TYPE"SMLF"
MATERIAL"EMPTY"
NEEDS_NO_SIZE"TRUE"
SEC_TYPE""
CDS_LMAN_SYM_OUTLINE"-75,50,75,-50"
CDS_LIB"pure_quanta"
PART_NUMBER"BC000530Z41";
"C"
$PN"2"30;
"A"
$PN"1"170;
%"VCC_CORE"
"1","(-2325,1475)","0","mstr_symbols","I550";
;
HDL_POWER"P3V3_AUX"
VOLTAGE"3.3"
ROOM"PVCCINFAON_CPU0_CTRL"
CDS_LIB"mstr_symbols";
"A"30;
%"Q_RES"
"1","(-8125,2875)","0","pure_quanta","I554";
;
LOCATION"R1674"
SEC"1"
PACK_TYPE"0402LF"
VALUE"10"
MATERIAL"CHIP"
SEC_TYPE"0402LF"
TOLERANCE"1%"
WATTAGE"1/16W"
CDS_LIB"pure_quanta"
PART_NUMBER"CS01002FB07";
"B"
$PN"2"31;
"A"
$PN"1"18;
END.
